FILE_TYPE = CONNECTIVITY;
{Allegro Design Entry HDL 16.6-p007 (v16-6-112F) 10/10/2012}
"PAGE_NUMBER" = 149;
0"NC";
1"GND\g";
2"P3V3_STBY\g";
3"VCC_VA_3V3\g";
4"GND\g";
5"P3V3_USB2A_ALG\g";
6"P3V3_STBY\g";
7"VCC_A_1V1\g";
8"GND\g";
9"P1V2_AUX_BMC\g";
10"GND\g";
11"GND\g";
12"GND\g";
13"P1V15_AUX_BMC\g";
14"P3V3_STBY\g";
15"VCC_DACAV3V3\g";
16"GND\g";
17"P3V3_STBY\g";
18"GND\g";
19"P1V15_AUX_BMC\g";
20"P3V3_STBY\g";
21"VCC_ADCAV3V3\g";
22"GND\g";
23"VCC_D_3V3\g";
24"GND\g";
25"VCC_PA_3V3\g";
26"GND\g";
27"P3V3_STBY\g";
28"P3V3_STBY\g";
29"P3V3_STBY\g";
%"CAP"
"1","(550,5400)","0","mstr_discrete","I1";
;
LOCATION"C25W30"
VALUE"4.7UF"
PART_NUMBER"E15431-003"
PACK_TYPE"0603"
VOLTAGE"6.3V"
TOLERANCE"10%"
MATERIAL"X6S"
CDS_SEC"1"
$SEC"1"
CDS_LOCATION"C25W30"
CDS_LIB"mstr_discrete";
"A"
$PN"1"19;
"B"
$PN"2"1;
%"CAP"
"1","(-650,2900)","0","mstr_discrete","I100";
;
CDS_SEC"1"
$SEC"1"
CDS_LOCATION"C25W43"
PACK_TYPE"0402"
MATERIAL"X6S"
TOLERANCE"10%"
VOLTAGE"16V"
VALUE"1.0UF"
LOCATION"C25W43"
PART_NUMBER"D97712-011"
ROOM"PROC_SIDEBAND"
BOM_COST"PROC"
CDS_LIB"mstr_discrete";
"A"
$PN"1"23;
"B"
$PN"2"18;
%"CAP"
"1","(-350,2900)","0","mstr_discrete","I101";
;
CDS_SEC"1"
$SEC"1"
CDS_LOCATION"C25W44"
PART_NUMBER"D97712-011"
VALUE"1.0UF"
TOLERANCE"10%"
VOLTAGE"16V"
MATERIAL"X6S"
PACK_TYPE"0402"
LOCATION"C25W44"
BOM_COST"PROC"
ROOM"PROC_SIDEBAND"
CDS_LIB"mstr_discrete";
"A"
$PN"1"23;
"B"
$PN"2"18;
%"CAP"
"1","(-675,4100)","0","mstr_discrete","I102";
;
CDS_SEC"1"
$SEC"1"
CDS_LOCATION"C25W33"
PACK_TYPE"0402"
MATERIAL"X6S"
LOCATION"C25W33"
VALUE"1.0UF"
VOLTAGE"16V"
TOLERANCE"10%"
PART_NUMBER"D97712-011"
ROOM"PROC_SIDEBAND"
BOM_COST"PROC"
CDS_LIB"mstr_discrete";
"A"
$PN"1"21;
"B"
$PN"2"22;
%"CAP"
"1","(-2250,5400)","0","mstr_discrete","I103";
;
CDS_SEC"1"
$SEC"1"
CDS_LOCATION"C25W23"
VOLTAGE"16V"
VALUE"1.0UF"
LOCATION"C25W23"
PACK_TYPE"0402"
TOLERANCE"10%"
PART_NUMBER"D97712-011"
MATERIAL"X6S"
ROOM"PROC_SIDEBAND"
BOM_COST"PROC"
CDS_LIB"mstr_discrete";
"A"
$PN"1"19;
"B"
$PN"2"1;
%"CAP"
"1","(-1850,5400)","0","mstr_discrete","I104";
;
CDS_SEC"1"
$SEC"1"
CDS_LOCATION"C25W24"
TOLERANCE"10%"
LOCATION"C25W24"
PART_NUMBER"D97712-011"
VALUE"1.0UF"
VOLTAGE"16V"
MATERIAL"X6S"
PACK_TYPE"0402"
BOM_COST"PROC"
ROOM"PROC_SIDEBAND"
CDS_LIB"mstr_discrete";
"A"
$PN"1"19;
"B"
$PN"2"1;
%"CAP"
"1","(-1450,5400)","0","mstr_discrete","I105";
;
CDS_SEC"1"
$SEC"1"
CDS_LOCATION"C25W25"
PACK_TYPE"0402"
VOLTAGE"16V"
TOLERANCE"10%"
VALUE"1.0UF"
LOCATION"C25W25"
PART_NUMBER"D97712-011"
MATERIAL"X6S"
ROOM"PROC_SIDEBAND"
BOM_COST"PROC"
CDS_LIB"mstr_discrete";
"A"
$PN"1"19;
"B"
$PN"2"1;
%"CAP"
"1","(-1050,5400)","0","mstr_discrete","I106";
;
CDS_SEC"1"
$SEC"1"
CDS_LOCATION"C25W26"
LOCATION"C25W26"
TOLERANCE"10%"
MATERIAL"X6S"
PART_NUMBER"D97712-011"
PACK_TYPE"0402"
VOLTAGE"16V"
VALUE"1.0UF"
BOM_COST"PROC"
ROOM"PROC_SIDEBAND"
CDS_LIB"mstr_discrete";
"A"
$PN"1"19;
"B"
$PN"2"1;
%"CAP"
"1","(-650,5400)","0","mstr_discrete","I107";
;
CDS_SEC"1"
$SEC"1"
CDS_LOCATION"C25W27"
VOLTAGE"16V"
TOLERANCE"10%"
VALUE"1.0UF"
LOCATION"C25W27"
MATERIAL"X6S"
PART_NUMBER"D97712-011"
PACK_TYPE"0402"
ROOM"PROC_SIDEBAND"
BOM_COST"PROC"
CDS_LIB"mstr_discrete";
"A"
$PN"1"19;
"B"
$PN"2"1;
%"CAP"
"1","(-250,5400)","0","mstr_discrete","I108";
;
CDS_SEC"1"
$SEC"1"
CDS_LOCATION"C25W28"
LOCATION"C25W28"
TOLERANCE"10%"
VOLTAGE"16V"
VALUE"1.0UF"
MATERIAL"X6S"
PACK_TYPE"0402"
PART_NUMBER"D97712-011"
BOM_COST"PROC"
ROOM"PROC_SIDEBAND"
CDS_LIB"mstr_discrete";
"A"
$PN"1"19;
"B"
$PN"2"1;
%"CAP"
"1","(1475,1725)","0","mstr_discrete","I109";
;
CDS_SEC"1"
$SEC"1"
CDS_LOCATION"C25W60"
PART_NUMBER"D97712-011"
MATERIAL"X6S"
TOLERANCE"10%"
LOCATION"C25W60"
VALUE"1.0UF"
VOLTAGE"16V"
PACK_TYPE"0402"
CDS_LIB"mstr_discrete"
BOM_COST"PROC"
ROOM"PROC_SIDEBAND";
"A"
$PN"1"17;
"B"
$PN"2"12;
%"CAP"
"1","(775,4000)","0","mstr_discrete","I110";
;
CDS_SEC"1"
$SEC"1"
CDS_LOCATION"C25W35"
PART_NUMBER"D97712-011"
VOLTAGE"16V"
VALUE"1.0UF"
LOCATION"C25W35"
MATERIAL"X6S"
TOLERANCE"10%"
PACK_TYPE"0402"
ROOM"PROC_SIDEBAND"
BOM_COST"PROC"
CDS_LIB"mstr_discrete";
"A"
$PN"1"15;
"B"
$PN"2"16;
%"CAP"
"1","(2325,3000)","0","mstr_discrete","I112";
;
CDS_SEC"1"
$SEC"1"
CDS_LOCATION"C25W48"
TOLERANCE"10%"
PART_NUMBER"D97712-011"
VALUE"1.0UF"
VOLTAGE"16V"
MATERIAL"X6S"
PACK_TYPE"0402"
LOCATION"C25W48"
BOM_COST"PROC"
ROOM"PROC_SIDEBAND"
CDS_LIB"mstr_discrete";
"A"
$PN"1"14;
"B"
$PN"2"10;
%"CAP"
"1","(2775,3975)","0","mstr_discrete","I113";
;
CDS_SEC"1"
$SEC"1"
CDS_LOCATION"C25W37"
VALUE"1.0UF"
VOLTAGE"16V"
TOLERANCE"10%"
LOCATION"C25W37"
PACK_TYPE"0402"
MATERIAL"X6S"
PART_NUMBER"D97712-011"
BOM_COST"PROC"
ROOM"PROC_SIDEBAND"
CDS_LIB"mstr_discrete";
"A"
$PN"1"7;
"B"
$PN"2"8;
%"CAP"
"1","(3950,2900)","0","mstr_discrete","I114";
;
CDS_SEC"1"
$SEC"1"
CDS_LOCATION"C25W51"
PART_NUMBER"D97712-011"
TOLERANCE"10%"
VOLTAGE"16V"
MATERIAL"X6S"
PACK_TYPE"0402"
LOCATION"C25W51"
VALUE"1.0UF"
ROOM"PROC_SIDEBAND"
BOM_COST"PROC"
CDS_LIB"mstr_discrete";
"A"
$PN"1"9;
"B"
$PN"2"24;
%"CAP"
"1","(4800,5300)","0","mstr_discrete","I115";
;
CDS_SEC"1"
$SEC"1"
CDS_LOCATION"C25W71"
LOCATION"C25W71"
VOLTAGE"16V"
TOLERANCE"10%"
VALUE"1.0UF"
PACK_TYPE"0402"
PART_NUMBER"D97712-011"
MATERIAL"X6S"
ROOM"PROC_SIDEBAND"
BOM_COST"PROC"
CDS_LIB"mstr_discrete";
"A"
$PN"1"5;
"B"
$PN"2"11;
%"CAP"
"1","(2150,5175)","0","mstr_discrete","I116";
;
CDS_SEC"1"
$SEC"1"
CDS_LOCATION"C25W66"
VOLTAGE"16V"
VALUE"1.0UF"
LOCATION"C25W66"
TOLERANCE"10%"
PACK_TYPE"0402"
MATERIAL"X6S"
PART_NUMBER"D97712-011"
ROOM"PROC_SIDEBAND"
BOM_COST"PROC"
CDS_LIB"mstr_discrete";
"A"
$PN"1"3;
"B"
$PN"2"4;
%"CAP"
"1","(2400,5175)","0","mstr_discrete","I117";
;
CDS_SEC"1"
$SEC"1"
CDS_LOCATION"C25W67"
VALUE"1.0UF"
TOLERANCE"10%"
VOLTAGE"16V"
LOCATION"C25W67"
PACK_TYPE"0402"
PART_NUMBER"D97712-011"
MATERIAL"X6S"
BOM_COST"PROC"
ROOM"PROC_SIDEBAND"
CDS_LIB"mstr_discrete";
"A"
$PN"1"3;
"B"
$PN"2"4;
%"CAP"
"1","(4250,2900)","0","mstr_discrete","I118";
;
CDS_SEC"1"
$SEC"1"
CDS_LOCATION"C25W52"
LOCATION"C25W52"
PART_NUMBER"D97712-011"
VALUE"1.0UF"
TOLERANCE"10%"
VOLTAGE"16V"
MATERIAL"X6S"
PACK_TYPE"0402"
CDS_LIB"mstr_discrete"
BOM_COST"PROC"
ROOM"PROC_SIDEBAND";
"A"
$PN"1"9;
"B"
$PN"2"24;
%"CAP_A"
"1","(-1475,4125)","0","dev_discrete","I119";
;
TOLERANCE"10%"
MATERIAL"X7R"
PACK_TYPE"0402V"
VOLTAGE"16V"
PART_NUMBER"A36096-030"
VALUE"0.1UF"
LOCATION"C25W31"
CDS_LOCATION"C25W31"
SEC"1"
SEC_TYPE"0402V"
ROOM"VDDQ_KLM_PWR_VR"
CDS_SEC"1"
CDS_LIB"dev_discrete";
"B"
$PN"2"22;
"A"
$PN"1"21;
%"CAP_A"
"1","(425,4000)","0","dev_discrete","I120";
;
TOLERANCE"10%"
MATERIAL"X7R"
PACK_TYPE"0402V"
VOLTAGE"16V"
PART_NUMBER"A36096-030"
VALUE"0.1UF"
LOCATION"C25W34"
CDS_LOCATION"C25W34"
SEC"1"
SEC_TYPE"0402V"
ROOM"VDDQ_KLM_PWR_VR"
CDS_SEC"1"
CDS_LIB"dev_discrete";
"B"
$PN"2"16;
"A"
$PN"1"15;
%"CAP_A"
"1","(3325,3975)","0","dev_discrete","I121";
;
VOLTAGE"16V"
TOLERANCE"10%"
MATERIAL"X7R"
PACK_TYPE"0402V"
LOCATION"C25W38"
VALUE"0.1UF"
PART_NUMBER"A36096-030"
CDS_LOCATION"C25W38"
SEC"1"
SEC_TYPE"0402V"
ROOM"VDDQ_KLM_PWR_VR"
CDS_SEC"1"
CDS_LIB"dev_discrete";
"B"
$PN"2"8;
"A"
$PN"1"7;
%"CAP_A"
"1","(-100,2900)","0","dev_discrete","I122";
;
TOLERANCE"10%"
VOLTAGE"16V"
MATERIAL"X7R"
PACK_TYPE"0402V"
PART_NUMBER"A36096-030"
VALUE"0.1UF"
LOCATION"C25W45"
CDS_LOCATION"C25W45"
SEC"1"
SEC_TYPE"0402V"
ROOM"VDDQ_KLM_PWR_VR"
CDS_SEC"1"
CDS_LIB"dev_discrete";
"B"
$PN"2"18;
"A"
$PN"1"23;
%"CAP_A"
"1","(2875,3000)","0","dev_discrete","I123";
;
MATERIAL"X7R"
VALUE"0.1UF"
PACK_TYPE"0402V"
LOCATION"C25W49"
VOLTAGE"16V"
TOLERANCE"10%"
PART_NUMBER"A36096-030"
CDS_LOCATION"C25W49"
CDS_LIB"dev_discrete"
CDS_SEC"1"
ROOM"VDDQ_KLM_PWR_VR"
SEC_TYPE"0402V"
SEC"1";
"B"
$PN"2"10;
"A"
$PN"1"14;
%"CAP_A"
"1","(5000,2925)","0","dev_discrete","I124";
;
VOLTAGE"16V"
LOCATION"C25W55"
VALUE"0.1UF"
TOLERANCE"10%"
MATERIAL"X7R"
PART_NUMBER"A36096-030"
PACK_TYPE"0402V"
CDS_LOCATION"C25W55"
SEC"1"
SEC_TYPE"0402V"
ROOM"VDDQ_KLM_PWR_VR"
CDS_SEC"1"
CDS_LIB"dev_discrete";
"B"
$PN"2"24;
"A"
$PN"1"9;
%"CAP_A"
"1","(-1150,1850)","0","dev_discrete","I125";
;
PACK_TYPE"0402V"
LOCATION"C25W58"
VALUE"0.1UF"
VOLTAGE"16V"
TOLERANCE"10%"
PART_NUMBER"A36096-030"
MATERIAL"X7R"
CDS_LOCATION"C25W58"
SEC"1"
SEC_TYPE"0402V"
ROOM"VDDQ_KLM_PWR_VR"
CDS_SEC"1"
CDS_LIB"dev_discrete";
"B"
$PN"2"26;
"A"
$PN"1"25;
%"CAP_A"
"1","(2025,1750)","0","dev_discrete","I126";
;
LOCATION"C25W61"
TOLERANCE"10%"
MATERIAL"X7R"
PACK_TYPE"0402V"
VOLTAGE"16V"
PART_NUMBER"A36096-030"
VALUE"0.1UF"
CDS_LOCATION"C25W61"
SEC"1"
SEC_TYPE"0402V"
ROOM"VDDQ_KLM_PWR_VR"
CDS_SEC"1"
CDS_LIB"dev_discrete";
"B"
$PN"2"12;
"A"
$PN"1"17;
%"CAP_A"
"1","(2700,5175)","0","dev_discrete","I128";
;
TOLERANCE"10%"
VOLTAGE"16V"
LOCATION"C25W68"
VALUE"0.1UF"
PART_NUMBER"A36096-030"
PACK_TYPE"0402V"
MATERIAL"X7R"
CDS_LOCATION"C25W68"
CDS_LIB"dev_discrete"
CDS_SEC"1"
ROOM"VDDQ_KLM_PWR_VR"
SEC_TYPE"0402V"
SEC"1";
"B"
$PN"2"4;
"A"
$PN"1"3;
%"CAP"
"1","(150,5400)","0","mstr_discrete","I129";
;
CDS_SEC"1"
PART_NUMBER"E15431-001"
PACK_TYPE"0603LF"
LOCATION"C25W29"
VALUE"10UF"
MATERIAL"X6S"
TOLERANCE"20%"
VOLTAGE"4V"
CDS_LIB"mstr_discrete"
SEC_TYPE"0603LF"
BOM_COST"PROC_SOCKET"
SEC"1"
ROOM"CPU0"
CDS_LOCATION"C25W29";
"A"
$PN"1"19;
"B"
$PN"2"1;
%"CAP"
"1","(-1450,1825)","0","mstr_discrete","I130";
;
CDS_SEC"1"
LOCATION"C25W57"
MATERIAL"COG"
PART_NUMBER"A36095-026"
VALUE"100.0PF"
PACK_TYPE"0402LF"
VOLTAGE"50V"
TOLERANCE"5%"
SEC_TYPE"0402LF"
SEC"1"
BOM_COST"SM_CONTROLLER"
ROOM"BMC"
CDS_LIB"mstr_discrete"
CDS_LOCATION"C25W57";
"A"
$PN"1"25;
"B"
$PN"2"26;
%"P3V3_STBY"
"1","(3800,5650)","0","mstr_symbols","I14";
;
VOLTAGE"3.3V"
HDL_POWER"P3V3_STBY"
BODY_TYPE"PLUMBING"
SIZE"1B"
CDS_LIB"mstr_symbols";
"G\NAC"2;
%"W_VCC_CIRCLE"
"1","(3100,5650)","0","w_power","I16";
;
HDL_POWER"VCC_VA_3V3"
BODY_TYPE"PLUMBING"
CDS_LIB"w_power"
CDS_LMAN_SYM_OUTLINE"-100,100,100,-100";
"VCC_CIRCLE \B"3;
%"CAP"
"1","(3100,5175)","0","mstr_discrete","I17";
;
PART_NUMBER"E15431-003"
PACK_TYPE"0603"
MATERIAL"X6S"
LOCATION"C25W69"
VALUE"4.7UF"
VOLTAGE"6.3V"
TOLERANCE"10%"
CDS_SEC"1"
$SEC"1"
CDS_LOCATION"C25W69"
CDS_LIB"mstr_discrete";
"A"
$PN"1"3;
"B"
$PN"2"4;
%"GND"
"1","(3100,4700)","0","mstr_symbols","I18";
;
HDL_POWER"GND"
SIZE"1B"
CDS_LIB"mstr_symbols"
BODY_TYPE"PLUMBING"
VOLTAGE"0.0V";
"A\NAC"4;
%"W_VCC_CIRCLE"
"1","(4800,5600)","0","w_power","I2";
;
HDL_POWER"P3V3_USB2A_ALG"
BODY_TYPE"PLUMBING"
CDS_LMAN_SYM_OUTLINE"-100,100,100,-100"
CDS_LIB"w_power";
"VCC_CIRCLE \B"5;
%"HCB1608KF-800T30-GP"
"1","(1500,5500)","1","w_hdl","I22";
;
LOCATION"FB2T1"
VALUE"HCB1608KF-800T30-GP"
ATTRIBUTE"80OHM@100MHZ"
PACK_SIZE"DCR=4MOHM"
RATED"3A"
CDS_SEC"1"
$SEC"1"
CDS_LOCATION"FB2T1"
PACK_TYPE"DISCRET-G9"
PART_NUMBER"68.00230.231"
CDS_LMAN_SYM_OUTLINE"-50,100,50,-100"
CDS_LIB"w_hdl";
"2"
$PN"2"3;
"1"
$PN"1"6;
%"P3V3_STBY"
"1","(1200,5650)","0","mstr_symbols","I23";
;
VOLTAGE"3.3V"
CDS_LIB"mstr_symbols"
HDL_POWER"P3V3_STBY"
BODY_TYPE"PLUMBING"
SIZE"1B";
"G\NAC"6;
%"GND"
"1","(550,5075)","0","mstr_symbols","I24";
;
CDS_LIB"mstr_symbols"
SIZE"1B"
HDL_POWER"GND"
BODY_TYPE"PLUMBING"
VOLTAGE"0.0V";
"A\NAC"1;
%"CAP"
"1","(3725,3975)","0","mstr_discrete","I25";
;
VOLTAGE"6.3V"
MATERIAL"X6S"
PACK_TYPE"0603"
TOLERANCE"10%"
PART_NUMBER"E15431-003"
LOCATION"C25W39"
VALUE"4.7UF"
CDS_SEC"1"
$SEC"1"
CDS_LOCATION"C25W39"
CDS_LIB"mstr_discrete";
"A"
$PN"1"7;
"B"
$PN"2"8;
%"W_VCC_CIRCLE"
"1","(3725,4450)","0","w_power","I26";
;
HDL_POWER"VCC_A_1V1"
CDS_LMAN_SYM_OUTLINE"-100,100,100,-100"
CDS_LIB"w_power"
BODY_TYPE"PLUMBING";
"VCC_CIRCLE \B"7;
%"GND"
"1","(3725,3600)","0","mstr_symbols","I27";
;
VOLTAGE"0.0V"
BODY_TYPE"PLUMBING"
CDS_LIB"mstr_symbols"
SIZE"1B"
HDL_POWER"GND";
"A\NAC"8;
%"W_VCC_CIRCLE"
"1","(3950,3350)","0","w_power","I29";
;
HDL_POWER"P1V2_AUX_BMC"
BODY_TYPE"PLUMBING"
CDS_LMAN_SYM_OUTLINE"-100,100,100,-100"
CDS_LIB"w_power";
"VCC_CIRCLE \B"9;
%"CAP"
"1","(3275,3000)","0","mstr_discrete","I31";
;
LOCATION"C25W50"
PART_NUMBER"E15431-003"
PACK_TYPE"0603"
MATERIAL"X6S"
TOLERANCE"10%"
VOLTAGE"6.3V"
VALUE"4.7UF"
CDS_SEC"1"
$SEC"1"
CDS_LOCATION"C25W50"
CDS_LIB"mstr_discrete";
"A"
$PN"1"14;
"B"
$PN"2"10;
%"GND"
"1","(3275,2625)","0","mstr_symbols","I32";
;
VOLTAGE"0.0V"
BODY_TYPE"PLUMBING"
HDL_POWER"GND"
SIZE"1B"
CDS_LIB"mstr_symbols";
"A\NAC"10;
%"GND"
"1","(4800,4900)","0","mstr_symbols","I4";
;
HDL_POWER"GND"
SIZE"1B"
BODY_TYPE"PLUMBING"
VOLTAGE"0.0V"
CDS_LIB"mstr_symbols";
"A\NAC"11;
%"CAP"
"1","(2425,1750)","0","mstr_discrete","I40";
;
LOCATION"C25W62"
VALUE"4.7UF"
VOLTAGE"6.3V"
PART_NUMBER"E15431-003"
PACK_TYPE"0603"
MATERIAL"X6S"
TOLERANCE"10%"
CDS_SEC"1"
$SEC"1"
CDS_LOCATION"C25W62"
CDS_LIB"mstr_discrete";
"A"
$PN"1"17;
"B"
$PN"2"12;
%"GND"
"1","(2425,1375)","0","mstr_symbols","I41";
;
VOLTAGE"0.0V"
BODY_TYPE"PLUMBING"
CDS_LIB"mstr_symbols"
HDL_POWER"GND"
SIZE"1B";
"A\NAC"12;
%"HCB1608KF-800T30-GP"
"1","(2325,4300)","1","w_hdl","I42";
;
RATED"3A"
ATTRIBUTE"80OHM@100MHZ"
LOCATION"FB2T7"
PACK_SIZE"DCR=4MOHM"
VALUE"HCB1608KF-800T30-GP"
CDS_SEC"1"
$SEC"1"
CDS_LOCATION"FB2T7"
PART_NUMBER"68.00230.231"
PACK_TYPE"DISCRET-G9"
CDS_LMAN_SYM_OUTLINE"-50,100,50,-100"
CDS_LIB"w_hdl";
"2"
$PN"2"7;
"1"
$PN"1"13;
%"W_VCC_CIRCLE"
"1","(2025,4400)","0","w_power","I43";
;
HDL_POWER"P1V15_AUX_BMC"
CDS_LIB"w_power"
CDS_LMAN_SYM_OUTLINE"-100,100,100,-100"
BODY_TYPE"PLUMBING";
"VCC_CIRCLE \B"13;
%"P3V3_STBY"
"1","(1575,3475)","0","mstr_symbols","I44";
;
VOLTAGE"3.3V"
SIZE"1B"
BODY_TYPE"PLUMBING"
HDL_POWER"P3V3_STBY"
CDS_LIB"mstr_symbols";
"G\NAC"14;
%"W_VCC_CIRCLE"
"1","(1125,4450)","0","w_power","I45";
;
HDL_POWER"VCC_DACAV3V3"
BODY_TYPE"PLUMBING"
CDS_LMAN_SYM_OUTLINE"-100,100,100,-100"
CDS_LIB"w_power";
"VCC_CIRCLE \B"15;
%"CAP"
"1","(1125,4000)","0","mstr_discrete","I46";
;
PART_NUMBER"E15431-003"
LOCATION"C25W36"
VALUE"4.7UF"
VOLTAGE"6.3V"
TOLERANCE"10%"
MATERIAL"X6S"
PACK_TYPE"0603"
CDS_SEC"1"
$SEC"1"
CDS_LOCATION"C25W36"
CDS_LIB"mstr_discrete";
"A"
$PN"1"15;
"B"
$PN"2"16;
%"GND"
"1","(1125,3475)","0","mstr_symbols","I49";
;
VOLTAGE"0.0V"
BODY_TYPE"PLUMBING"
CDS_LIB"mstr_symbols"
SIZE"1B"
HDL_POWER"GND";
"A\NAC"16;
%"CAP"
"1","(4300,5300)","0","mstr_discrete","I5";
;
LOCATION"C25W70"
VALUE"4.7UF"
VOLTAGE"6.3V"
TOLERANCE"10%"
MATERIAL"X6S"
PACK_TYPE"0603"
PART_NUMBER"E15431-003"
CDS_SEC"1"
$SEC"1"
CDS_LOCATION"C25W70"
CDS_LIB"mstr_discrete";
"A"
$PN"1"5;
"B"
$PN"2"11;
%"CAP"
"1","(550,2900)","0","mstr_discrete","I50";
;
VALUE"4.7UF"
VOLTAGE"6.3V"
TOLERANCE"10%"
LOCATION"C25W47"
MATERIAL"X6S"
PACK_TYPE"0603"
PART_NUMBER"E15431-003"
CDS_SEC"1"
$SEC"1"
CDS_LOCATION"C25W47"
CDS_LIB"mstr_discrete";
"A"
$PN"1"23;
"B"
$PN"2"18;
%"CAP"
"1","(250,2900)","0","mstr_discrete","I51";
;
LOCATION"C25W46"
PART_NUMBER"C95333-007"
PACK_TYPE"0805"
MATERIAL"X6S"
TOLERANCE"10%"
VALUE"10UF"
VOLTAGE"16V"
CDS_SEC"1"
$SEC"1"
CDS_LOCATION"C25W46"
BOM_COST"SM_CONTROLLER"
ROOM"BMC"
CDS_LIB"mstr_discrete";
"A"
$PN"1"23;
"B"
$PN"2"18;
%"P3V3_STBY"
"1","(725,2225)","0","mstr_symbols","I54";
;
VOLTAGE"3.3V"
CDS_LIB"mstr_symbols"
SIZE"1B"
BODY_TYPE"PLUMBING"
HDL_POWER"P3V3_STBY";
"G\NAC"17;
%"GND"
"1","(475,2400)","0","mstr_symbols","I55";
;
VOLTAGE"0.0V"
BODY_TYPE"PLUMBING"
SIZE"1B"
HDL_POWER"GND"
CDS_LIB"mstr_symbols";
"A\NAC"18;
%"W_VCC_CIRCLE"
"1","(-2250,5625)","0","w_power","I62";
;
HDL_POWER"P1V15_AUX_BMC"
CDS_LIB"w_power"
CDS_LMAN_SYM_OUTLINE"-100,100,100,-100"
BODY_TYPE"PLUMBING";
"VCC_CIRCLE \B"19;
%"P3V3_STBY"
"1","(-175,4425)","0","mstr_symbols","I65";
;
VOLTAGE"3.3V"
CDS_LIB"mstr_symbols"
HDL_POWER"P3V3_STBY"
BODY_TYPE"PLUMBING"
SIZE"1B";
"G\NAC"20;
%"W_VCC_CIRCLE"
"1","(-675,4475)","0","w_power","I66";
;
HDL_POWER"VCC_ADCAV3V3"
BODY_TYPE"PLUMBING"
CDS_LIB"w_power"
CDS_LMAN_SYM_OUTLINE"-100,100,100,-100";
"VCC_CIRCLE \B"21;
%"GND"
"1","(-675,3600)","0","mstr_symbols","I68";
;
VOLTAGE"0.0V"
BODY_TYPE"PLUMBING"
CDS_LIB"mstr_symbols"
SIZE"1B"
HDL_POWER"GND";
"A\NAC"22;
%"W_VCC_CIRCLE"
"1","(-100,3350)","0","w_power","I69";
;
HDL_POWER"VCC_D_3V3"
CDS_LMAN_SYM_OUTLINE"-100,100,100,-100"
CDS_LIB"w_power"
BODY_TYPE"PLUMBING";
"VCC_CIRCLE \B"23;
%"GND"
"1","(5000,2550)","0","mstr_symbols","I7";
;
CDS_LIB"mstr_symbols"
HDL_POWER"GND"
SIZE"1B"
BODY_TYPE"PLUMBING"
VOLTAGE"0.0V";
"A\NAC"24;
%"W_VCC_CIRCLE"
"1","(-550,2300)","0","w_power","I78";
;
HDL_POWER"VCC_PA_3V3"
CDS_LIB"w_power"
CDS_LMAN_SYM_OUTLINE"-100,100,100,-100"
BODY_TYPE"PLUMBING";
"VCC_CIRCLE \B"25;
%"CAP"
"1","(-550,1850)","0","mstr_discrete","I79";
;
CDS_SEC"1"
PACK_TYPE"0603"
LOCATION"C25W59"
POP"NOPOP"
VALUE"4.7UF"
VOLTAGE"6.3V"
TOLERANCE"10%"
MATERIAL"X6S"
PART_NUMBER"E15431-003"
SEC_TYPE"0603"
SEC"1"
CDS_LOCATION"C25W59"
CDS_LIB"mstr_discrete";
"A"
$PN"1"25;
"B"
$PN"2"26;
%"GND"
"1","(-550,1425)","0","mstr_symbols","I80";
;
SIZE"1B"
HDL_POWER"GND"
CDS_LIB"mstr_symbols"
BODY_TYPE"PLUMBING"
VOLTAGE"0.0V";
"A\NAC"26;
%"P3V3_STBY"
"1","(-2350,4550)","0","mstr_symbols","I84";
;
HDL_POWER"P3V3_STBY"
BODY_TYPE"PLUMBING"
SIZE"1B"
CDS_LIB"mstr_symbols"
VOLTAGE"3.3V";
"G\NAC"27;
%"HCB1608KF-800T30-GP"
"1","(-2075,4400)","1","w_hdl","I85";
;
PACK_SIZE"DCR=4MOHM"
RATED"3A"
ATTRIBUTE"80OHM@100MHZ"
VALUE"HCB1608KF-800T30-GP"
LOCATION"FB2T3"
CDS_SEC"1"
$SEC"1"
CDS_LOCATION"FB2T3"
PACK_TYPE"DISCRET-G9"
PART_NUMBER"68.00230.231"
CDS_LIB"w_hdl"
CDS_LMAN_SYM_OUTLINE"-50,100,50,-100";
"2"
$PN"2"21;
"1"
$PN"1"27;
%"HCB1608KF-800T30-GP"
"1","(-2050,3200)","1","w_hdl","I86";
;
RATED"3A"
ATTRIBUTE"80OHM@100MHZ"
LOCATION"FB2T4"
VALUE"HCB1608KF-800T30-GP"
PACK_SIZE"DCR=4MOHM"
CDS_SEC"1"
$SEC"1"
CDS_LOCATION"FB2T4"
CDS_LIB"w_hdl"
CDS_LMAN_SYM_OUTLINE"-50,100,50,-100"
PACK_TYPE"DISCRET-G9"
PART_NUMBER"68.00230.231";
"2"
$PN"2"23;
"1"
$PN"1"28;
%"P3V3_STBY"
"1","(-2325,3350)","0","mstr_symbols","I87";
;
SIZE"1B"
BODY_TYPE"PLUMBING"
HDL_POWER"P3V3_STBY"
CDS_LIB"mstr_symbols"
VOLTAGE"3.3V";
"G\NAC"28;
%"HCB1608KF-800T30-GP"
"1","(-2025,2150)","1","w_hdl","I88";
;
LOCATION"FB2T5"
RATED"3A"
PACK_SIZE"DCR=4MOHM"
ATTRIBUTE"80OHM@100MHZ"
VALUE"HCB1608KF-800T30-GP"
CDS_SEC"1"
$SEC"1"
CDS_LOCATION"FB2T5"
PART_NUMBER"68.00230.231"
PACK_TYPE"DISCRET-G9"
CDS_LIB"w_hdl"
CDS_LMAN_SYM_OUTLINE"-50,100,50,-100";
"2"
$PN"2"25;
"1"
$PN"1"29;
%"P3V3_STBY"
"1","(-2325,2300)","0","mstr_symbols","I89";
;
HDL_POWER"P3V3_STBY"
BODY_TYPE"PLUMBING"
SIZE"1B"
CDS_LIB"mstr_symbols"
VOLTAGE"3.3V";
"G\NAC"29;
%"RES"
"1","(125,4275)","0","mstr_discrete","I90";
;
CDS_SEC"1"
$SEC"1"
CDS_LOCATION"R25W93"
PART_NUMBER"G22178-002"
LOCATION"R25W93"
PACK_TYPE"0603"
VALUE"0"
TOLERANCE"5.0%"
WATTAGE"1/10W"
MATERIAL"CHIP"
CDS_LIB"mstr_discrete"
BOM_COST"NT_GBE_BASE"
ROOM"NIC_SPRV";
"B"
$PN"2"15;
"A"
$PN"1"20;
%"RES"
"1","(4100,5500)","0","mstr_discrete","I91";
;
CDS_SEC"1"
$SEC"1"
CDS_LOCATION"R25W120"
PART_NUMBER"G22178-002"
VALUE"0"
LOCATION"R25W120"
PACK_TYPE"0603"
TOLERANCE"5.0%"
WATTAGE"1/10W"
MATERIAL"CHIP"
BOM_COST"NT_GBE_BASE"
ROOM"NIC_SPRV"
CDS_LIB"mstr_discrete";
"B"
$PN"2"5;
"A"
$PN"1"2;
%"CAP"
"1","(4500,2900)","0","mstr_discrete","I92";
;
CDS_SEC"1"
CDS_LOCATION"C25W53"
VALUE"1.0UF"
LOCATION"C25W53"
PACK_TYPE"0402"
PART_NUMBER"D97712-011"
MATERIAL"X6S"
VOLTAGE"16V"
TOLERANCE"10%"
ROOM"PROC_SIDEBAND"
BOM_COST"PROC"
SEC"1"
SEC_TYPE"0402"
CDS_LIB"mstr_discrete";
"A"
$PN"1"9;
"B"
$PN"2"24;
%"CAP"
"1","(-850,1850)","0","mstr_discrete","I93";
;
CDS_SEC"1"
$SEC"1"
CDS_LOCATION"C25W56"
TOLERANCE"10%"
MATERIAL"X6S"
PACK_TYPE"0402"
VOLTAGE"16V"
VALUE"1.0UF"
LOCATION"C25W56"
PART_NUMBER"D97712-011"
CDS_LIB"mstr_discrete"
ROOM"PROC_SIDEBAND"
BOM_COST"PROC";
"A"
$PN"1"25;
"B"
$PN"2"26;
%"CAP"
"1","(4750,2900)","0","mstr_discrete","I95";
;
CDS_SEC"1"
$SEC"1"
CDS_LOCATION"C25W54"
PACK_TYPE"0402"
PART_NUMBER"D97712-011"
MATERIAL"X6S"
TOLERANCE"10%"
VOLTAGE"16V"
VALUE"1.0UF"
LOCATION"C25W54"
BOM_COST"PROC"
ROOM"PROC_SIDEBAND"
CDS_LIB"mstr_discrete";
"A"
$PN"1"9;
"B"
$PN"2"24;
%"CAP"
"1","(-1450,2900)","0","mstr_discrete","I96";
;
CDS_SEC"1"
$SEC"1"
CDS_LOCATION"C25W40"
LOCATION"C25W40"
VALUE"1.0UF"
VOLTAGE"16V"
PART_NUMBER"D97712-011"
TOLERANCE"10%"
MATERIAL"X6S"
PACK_TYPE"0402"
BOM_COST"PROC"
ROOM"PROC_SIDEBAND"
CDS_LIB"mstr_discrete";
"A"
$PN"1"23;
"B"
$PN"2"18;
%"CAP"
"1","(-1150,2900)","0","mstr_discrete","I97";
;
CDS_SEC"1"
$SEC"1"
CDS_LOCATION"C25W41"
LOCATION"C25W41"
PART_NUMBER"D97712-011"
PACK_TYPE"0402"
MATERIAL"X6S"
VOLTAGE"16V"
TOLERANCE"10%"
VALUE"1.0UF"
ROOM"PROC_SIDEBAND"
BOM_COST"PROC"
CDS_LIB"mstr_discrete";
"A"
$PN"1"23;
"B"
$PN"2"18;
%"CAP"
"1","(-900,2900)","0","mstr_discrete","I98";
;
CDS_SEC"1"
$SEC"1"
CDS_LOCATION"C25W42"
PART_NUMBER"D97712-011"
VOLTAGE"16V"
VALUE"1.0UF"
LOCATION"C25W42"
PACK_TYPE"0402"
MATERIAL"X6S"
TOLERANCE"10%"
ROOM"PROC_SIDEBAND"
BOM_COST"PROC"
CDS_LIB"mstr_discrete";
"A"
$PN"1"23;
"B"
$PN"2"18;
%"CAP"
"1","(-1025,4100)","0","mstr_discrete","I99";
;
CDS_SEC"1"
$SEC"1"
CDS_LOCATION"C25W32"
TOLERANCE"10%"
LOCATION"C25W32"
PACK_TYPE"0402"
PART_NUMBER"D97712-011"
MATERIAL"X6S"
VALUE"1.0UF"
VOLTAGE"16V"
BOM_COST"PROC"
ROOM"PROC_SIDEBAND"
CDS_LIB"mstr_discrete";
"A"
$PN"1"21;
"B"
$PN"2"22;
END.
